FILE_TYPE = CONNECTIVITY;
{Allegro Design Entry HDL 16.6-p007 (v16-6-112F) 10/10/2012}
"PAGE_NUMBER" = 93;
0"NC";
1"PVCCIO_CPU1\g";
2"GND\g";
3"GND\g";
4"PVCCIO_CPU0\g";
5"P3V3\g";
6"GND\g";
7"PVCCIO_CPU0\g";
8"PVCCIO_CPU0\g";
9"GND\g";
10"H_CPU_ERR1_PCH_N";
11"H_CPU_ERR0_PCH_N";
12"FM_CPU_ERR1_LVT3_N";
13"FM_CPU_ERR0_LVT3_N";
14"FM_CPU1_PROCHOT_LVT3_N";
15"FM_CPU0_PROCHOT_LVT3_N";
16"FM_CPU_ERR0_LVT3_K_N";
17"FM_CPU1_PROCHOT_LVT3_K_N";
18"H_CPU1_PROCHOT_G_PCH_N";
19"PD_GTL2104_4_DIR";
20"P0V7_GTL2104_5_VREF"VOLTAGE"0.734";
21"FM_CPU0_PROCHOT_LVT3_K_N";
22"FM_CPU_ERR1_LVT3_K_N";
23"FM_CPU_ERR1_LVT3_R_N";
24"FM_CPU1_PROCHOT_LVT3_R_N";
25"FM_CPU0_PROCHOT_LVT3_R_N";
26"FM_CPU_ERR0_LVT3_R_N";
27"P0V7_GTL2104_5_VREF";
28"PD_GTL2104_4_DIR";
29"H_CPU0_PROCHOT_G_PCH_N";
30"H_CPU1_PROCHOT_G_R_N";
31"H_CPU0_PROCHOT_G_R_N";
32"H_CPU_ERR0_GTL_N";
33"H_CPU_ERR1_GTL_N";
34"H_CPU0_PROCHOT_G_N";
35"H_CPU1_PROCHOT_G_N";
36"H_CPU_ERR0_GTL_R_N";
37"H_CPU_ERR1_GTL_R_N";
38"FM_CPU_ERR1_LVT3_BMC_N";
39"FM_CPU_ERR1_PCH_N";
40"FM_CPU0_PROCHOT_LVT3_BMC_N";
41"FM_CPU1_PROCHOT_LVT3_BMC_N";
42"FM_CPU_ERR0_PCH_N";
43"FM_CPU0_PROCHOT_PCH_N";
44"FM_CPU1_PROCHOT_PCH_N";
45"FM_CPU_ERR0_LVT3_BMC_N";
46"H_CPU0_ERR0_G_N";
47"H_CPU1_ERR1_G_N";
48"H_CPU1_ERR0_G_N";
49"H_CPU0_ERR1_G_N";
50"FM_CPU_ERR0_LVT3_N";
51"FM_CPU_ERR1_LVT3_N";
52"FM_CPU0_PROCHOT_LVT3_N";
53"FM_CPU1_PROCHOT_LVT3_N";
%"RES"
"1","(-825,2175)","0","mstr_discrete","I102";
;
CDS_SEC"1"
CDS_LOCATION"R2T68"
SEC"1"
SEC_TYPE"0402"
CDS_LIB"mstr_discrete"
TOLERANCE"5%"
WATTAGE"1/16W"
PACK_TYPE"0402"
LOCATION"R2T68"
PART_NUMBER"G21497-005"
MATERIAL"CHIP"
VALUE"0.0";
"B"
$PN"2"30;
"A"
$PN"1"35;
%"RES"
"1","(-825,2300)","0","mstr_discrete","I103";
;
CDS_SEC"1"
CDS_LOCATION"R2T60"
PACK_TYPE"0402"
SEC"1"
SEC_TYPE"0402"
CDS_LIB"mstr_discrete"
TOLERANCE"5%"
WATTAGE"1/16W"
PART_NUMBER"G21497-005"
LOCATION"R2T60"
MATERIAL"CHIP"
VALUE"0.0";
"B"
$PN"2"31;
"A"
$PN"1"34;
%"PVCCIO_CPU1"
"1","(-2200,2800)","0","mstr_symbols","I105";
;
HDL_POWER"PVCCIO_CPU1"
CDS_LIB"mstr_symbols"
VOLTAGE"1.1V"
BODY_TYPE"PLUMBING";
"G\NAC"1;
%"RES"
"2","(-2200,2500)","0","mstr_discrete","I106";
;
CDS_SEC"1"
SEC_TYPE"0402"
SEC"1"
CDS_LOCATION"R7P28"
CDS_LIB"mstr_discrete"
BOM_COST"PROC_SIDEBAND"
ROOM"PROC_SIDEBAND"
WATTAGE"1/16W"
PACK_TYPE"0402"
VALUE"150.0"
LOCATION"R7P28"
PART_NUMBER"G21796-009"
MATERIAL"CHIP"
TOLERANCE"1%";
"A"
$PN"1"1;
"B"
$PN"2"35;
%"RES"
"2","(-1100,1900)","0","mstr_discrete","I107";
;
CDS_SEC"1"
CDS_LOCATION"R2T59"
SEC"1"
SEC_TYPE"0402"
CDS_LIB"mstr_discrete"
LOCATION"R2T59"
WATTAGE"1/16W"
TOLERANCE"5%"
VALUE"0.0"
MATERIAL"EMPTY"
PACK_TYPE"0402"
PART_NUMBER"G21497-005";
"A"
$PN"1"34;
"B"
$PN"2"29;
%"RES"
"2","(-1400,1900)","0","mstr_discrete","I108";
;
CDS_SEC"1"
CDS_LOCATION"R2T69"
SEC"1"
SEC_TYPE"0402"
CDS_LIB"mstr_discrete"
LOCATION"R2T69"
WATTAGE"1/16W"
PACK_TYPE"0402"
VALUE"0.0"
PART_NUMBER"G21497-005"
MATERIAL"EMPTY"
TOLERANCE"5%";
"A"
$PN"1"35;
"B"
$PN"2"18;
%"RES"
"2","(2025,2225)","0","mstr_discrete","I109";
;
CDS_SEC"1"
CDS_LOCATION"R2T71"
SEC"1"
SEC_TYPE"0402"
CDS_LIB"mstr_discrete"
PART_NUMBER"G21497-005"
LOCATION"R2T71"
VALUE"0.0"
WATTAGE"1/16W"
PACK_TYPE"0402"
MATERIAL"EMPTY"
TOLERANCE"5%";
"A"
$PN"1"21;
"B"
$PN"2"29;
%"RES"
"2","(2400,2225)","0","mstr_discrete","I110";
;
CDS_SEC"1"
CDS_LOCATION"R7D43"
SEC"1"
SEC_TYPE"0402"
CDS_LIB"mstr_discrete"
PART_NUMBER"G21497-005"
MATERIAL"EMPTY"
WATTAGE"1/16W"
LOCATION"R7D43"
VALUE"0.0"
TOLERANCE"5%"
PACK_TYPE"0402";
"A"
$PN"1"17;
"B"
$PN"2"18;
%"RES"
"1","(1875,3350)","0","mstr_discrete","I111";
;
CDS_SEC"1"
CDS_LOCATION"R2T65"
PACK_TYPE"0402"
SEC_TYPE"0402"
CDS_LIB"mstr_discrete"
SEC"1"
WATTAGE"1/16W"
TOLERANCE"5%"
PART_NUMBER"G21497-005"
LOCATION"R2T65"
MATERIAL"CHIP"
VALUE"0.0";
"B"
$PN"2"16;
"A"
$PN"1"26;
%"RES"
"1","(1875,3100)","0","mstr_discrete","I112";
;
CDS_SEC"1"
CDS_LOCATION"R2T66"
PACK_TYPE"0402"
SEC"1"
SEC_TYPE"0402"
CDS_LIB"mstr_discrete"
WATTAGE"1/16W"
TOLERANCE"5%"
PART_NUMBER"G21497-005"
LOCATION"R2T66"
VALUE"0.0"
MATERIAL"CHIP";
"B"
$PN"2"22;
"A"
$PN"1"23;
%"RES"
"1","(1875,2850)","0","mstr_discrete","I113";
;
CDS_SEC"1"
CDS_LOCATION"R2T67"
PACK_TYPE"0402"
SEC"1"
SEC_TYPE"0402"
CDS_LIB"mstr_discrete"
WATTAGE"1/16W"
TOLERANCE"5%"
PART_NUMBER"G21497-005"
LOCATION"R2T67"
MATERIAL"CHIP"
VALUE"0.0";
"B"
$PN"2"21;
"A"
$PN"1"25;
%"RES"
"1","(1875,2575)","0","mstr_discrete","I114";
;
CDS_SEC"1"
CDS_LOCATION"R7D41"
PACK_TYPE"0402"
SEC_TYPE"0402"
CDS_LIB"mstr_discrete"
SEC"1"
WATTAGE"1/16W"
TOLERANCE"5%"
PART_NUMBER"G21497-005"
LOCATION"R7D41"
VALUE"0.0"
MATERIAL"CHIP";
"B"
$PN"2"17;
"A"
$PN"1"24;
%"RES"
"1","(-2225,1450)","0","mstr_discrete","I119";
;
CDS_SEC"1"
CDS_LOCATION"R8F38"
SEC"1"
SEC_TYPE"0402"
CDS_LIB"mstr_discrete"
PACK_TYPE"0402"
PART_NUMBER"G21497-005"
MATERIAL"CHIP"
LOCATION"R8F38"
TOLERANCE"5%"
WATTAGE"1/16W"
VALUE"0.0";
"B"
$PN"2"45;
"A"
$PN"1"50;
%"RES"
"1","(-2225,1050)","0","mstr_discrete","I121";
;
CDS_SEC"1"
CDS_LOCATION"R2T64"
SEC_TYPE"0402"
SEC"1"
CDS_LIB"mstr_discrete"
PACK_TYPE"0402"
LOCATION"R2T64"
PART_NUMBER"G21497-005"
VALUE"0.0"
WATTAGE"1/16W"
MATERIAL"CHIP"
TOLERANCE"5%";
"B"
$PN"2"38;
"A"
$PN"1"51;
%"RES"
"1","(-2225,675)","0","mstr_discrete","I122";
;
CDS_SEC"1"
CDS_LOCATION"R1T36"
SEC"1"
SEC_TYPE"0402"
CDS_LIB"mstr_discrete"
PACK_TYPE"0402"
MATERIAL"CHIP"
LOCATION"R1T36"
TOLERANCE"5%"
PART_NUMBER"G21497-005"
VALUE"0.0"
WATTAGE"1/16W";
"B"
$PN"2"40;
"A"
$PN"1"52;
%"RES"
"1","(-2225,275)","0","mstr_discrete","I123";
;
CDS_SEC"1"
CDS_LOCATION"R1T37"
SEC_TYPE"0402"
SEC"1"
CDS_LIB"mstr_discrete"
PACK_TYPE"0402"
LOCATION"R1T37"
MATERIAL"CHIP"
TOLERANCE"5%"
PART_NUMBER"G21497-005"
VALUE"0.0"
WATTAGE"1/16W";
"B"
$PN"2"41;
"A"
$PN"1"53;
%"RES"
"2","(3700,425)","0","mstr_discrete","I127";
;
CDS_SEC"1"
ROOM"PROC_SIDEBAND"
CDS_LOCATION"R2T50"
SEC"1"
SEC_TYPE"0402"
BOM_COST"PROC"
CDS_LIB"mstr_discrete"
LOCATION"R2T50"
VALUE"1.00K"
WATTAGE"1/16W"
MATERIAL"CHIP"
PACK_TYPE"0402"
PART_NUMBER"G21796-026"
TOLERANCE"1%";
"A"
$PN"1"19;
"B"
$PN"2"2;
%"GND"
"1","(3700,225)","0","mstr_symbols","I128";
;
HDL_POWER"GND"
CDS_LIB"mstr_symbols"
VOLTAGE"0"
BODY_TYPE"PLUMBING"
SIZE"1B";
"A\NAC"2;
%"RES"
"1","(-2750,3200)","0","mstr_discrete","I13";
;
CDS_SEC"1"
SEC"1"
SEC_TYPE"0402"
CDS_LIB"mstr_discrete"
BOM_COST"PROC"
CDS_LOCATION"R2T27"
ROOM"PROC_SIDEBAND"
PART_NUMBER"G21497-005"
LOCATION"R2T27"
WATTAGE"1/16W"
TOLERANCE"5%"
PACK_TYPE"0402"
VALUE"0.0"
MATERIAL"CHIP";
"B"
$PN"2"37;
"A"
$PN"1"47;
%"RES"
"1","(-2225,1250)","0","mstr_discrete","I131";
;
CDS_SEC"1"
CDS_LOCATION"R8F37"
SEC"1"
SEC_TYPE"0402"
CDS_LIB"mstr_discrete"
PACK_TYPE"0402"
LOCATION"R8F37"
MATERIAL"EMPTY"
TOLERANCE"5%"
PART_NUMBER"G21497-005"
VALUE"0.0"
WATTAGE"1/16W";
"B"
$PN"2"42;
"A"
$PN"1"50;
%"RES"
"1","(-2225,850)","0","mstr_discrete","I133";
;
CDS_SEC"1"
CDS_LOCATION"R2T63"
SEC"1"
SEC_TYPE"0402"
CDS_LIB"mstr_discrete"
PACK_TYPE"0402"
LOCATION"R2T63"
MATERIAL"EMPTY"
TOLERANCE"5%"
PART_NUMBER"G21497-005"
VALUE"0.0"
WATTAGE"1/16W";
"B"
$PN"2"39;
"A"
$PN"1"51;
%"RES"
"1","(-2225,475)","0","mstr_discrete","I135";
;
CDS_SEC"1"
CDS_LOCATION"R1T35"
SEC"1"
SEC_TYPE"0402"
CDS_LIB"mstr_discrete"
PACK_TYPE"0402"
LOCATION"R1T35"
PART_NUMBER"G21497-005"
MATERIAL"EMPTY"
TOLERANCE"5%"
VALUE"0.0"
WATTAGE"1/16W";
"B"
$PN"2"43;
"A"
$PN"1"52;
%"RES"
"1","(-2225,75)","0","mstr_discrete","I137";
;
CDS_SEC"1"
CDS_LOCATION"R1T38"
SEC"1"
SEC_TYPE"0402"
CDS_LIB"mstr_discrete"
PACK_TYPE"0402"
LOCATION"R1T38"
MATERIAL"EMPTY"
TOLERANCE"5%"
PART_NUMBER"G21497-005"
VALUE"0.0"
WATTAGE"1/16W";
"B"
$PN"2"44;
"A"
$PN"1"53;
%"RES"
"2","(-2475,2525)","0","mstr_discrete","I143";
;
CDS_LOCATION"R2T72"
CDS_SEC"1"
SEC_TYPE"0402"
SEC"1"
CDS_LIB"mstr_discrete"
BOM_COST"PROC_SIDEBAND"
ROOM"PROC_SIDEBAND"
LOCATION"R2T72"
VALUE"150.0"
TOLERANCE"1%"
PART_NUMBER"G21796-009"
WATTAGE"1/16W"
MATERIAL"CHIP"
PACK_TYPE"0402";
"A"
$PN"1"7;
"B"
$PN"2"34;
%"RES"
"2","(-1900,2500)","0","mstr_discrete","I144";
;
CDS_LOCATION"R2T73"
CDS_SEC"1"
SEC"1"
SEC_TYPE"0402"
BOM_COST"PROC_SIDEBAND"
CDS_LIB"mstr_discrete"
ROOM"PROC_SIDEBAND"
VALUE"150.0"
LOCATION"R2T73"
PART_NUMBER"G21796-009"
MATERIAL"CHIP"
PACK_TYPE"0402"
WATTAGE"1/16W"
TOLERANCE"1%";
"A"
$PN"1"1;
"B"
$PN"2"35;
%"RES"
"1","(-2750,3425)","0","mstr_discrete","I15";
;
CDS_SEC"1"
SEC_TYPE"0402"
SEC"1"
CDS_LIB"mstr_discrete"
BOM_COST"PROC"
CDS_LOCATION"R2T32"
ROOM"PROC_SIDEBAND"
PART_NUMBER"G21497-005"
LOCATION"R2T32"
WATTAGE"1/16W"
TOLERANCE"5%"
PACK_TYPE"0402"
MATERIAL"CHIP"
VALUE"0.0";
"B"
$PN"2"37;
"A"
$PN"1"49;
%"RES"
"1","(-2750,3725)","0","mstr_discrete","I16";
;
CDS_SEC"1"
SEC_TYPE"0402"
SEC"1"
BOM_COST"PROC"
CDS_LIB"mstr_discrete"
ROOM"PROC_SIDEBAND"
CDS_LOCATION"R2T20"
PART_NUMBER"G21497-005"
WATTAGE"1/16W"
TOLERANCE"5%"
PACK_TYPE"0402"
LOCATION"R2T20"
MATERIAL"CHIP"
VALUE"0.0";
"B"
$PN"2"36;
"A"
$PN"1"48;
%"RES"
"1","(-2750,3975)","0","mstr_discrete","I23";
;
CDS_SEC"1"
SEC_TYPE"0402"
SEC"1"
CDS_LIB"mstr_discrete"
BOM_COST"PROC"
ROOM"PROC_SIDEBAND"
CDS_LOCATION"R2T17"
PART_NUMBER"G21497-005"
WATTAGE"1/16W"
TOLERANCE"5%"
PACK_TYPE"0402"
LOCATION"R2T17"
MATERIAL"CHIP"
VALUE"0.0";
"B"
$PN"2"36;
"A"
$PN"1"46;
%"GND"
"1","(-200,2825)","0","mstr_symbols","I29";
;
HDL_POWER"GND"
VOLTAGE"0"
CDS_LIB"mstr_symbols"
SIZE"1B"
BODY_TYPE"PLUMBING";
"A\NAC"3;
%"GTL2014"
"1","(425,3350)","2","mstr_digital","I30";
;
CDS_SEC"1"
PACK_TYPE"SM"
ROOM"PROC_SIDEBAND"
CDS_LOCATION"U2T4"
SEC"1"
SEC_TYPE"SM"
CDS_LIB"mstr_digital"
BOM_COST"PROC"
LOCATION"U2T4"
MATERIAL"IC"
PART_NUMBER"D66151-001";
"A0"
$PN"13"24;
"A1"
$PN"12"25;
"A3"
$PN"9"26;
"A2"
$PN"10"23;
"B2"
$PN"5"33;
"B3"
$PN"6"32;
"B0"
$PN"2"30;
"B1"
$PN"3"31;
"GND<1>"
$PN"8"3;
"GND<2>"
$PN"11"3;
"GND<0>"
$PN"7"3;
"VCC"
$PN"14"5;
"VREF"
$PN"4"27;
"DIR"
$PN"1"28;
%"RES"
"1","(2950,2850)","0","mstr_discrete","I39";
;
CDS_SEC"1"
SEC"1"
SEC_TYPE"0402"
CDS_LIB"mstr_discrete"
BOM_COST"PROC"
CDS_LOCATION"R2T38"
ROOM"PROC_SIDEBAND"
PACK_TYPE"0402"
PART_NUMBER"G21796-074"
LOCATION"R2T38"
TOLERANCE"1%"
MATERIAL"CHIP"
WATTAGE"1/16W"
VALUE"33.2";
"B"
$PN"2"15;
"A"
$PN"1"21;
%"RES"
"1","(2950,3100)","0","mstr_discrete","I40";
;
CDS_SEC"1"
SEC"1"
SEC_TYPE"0402"
BOM_COST"PROC"
CDS_LIB"mstr_discrete"
CDS_LOCATION"R2T33"
ROOM"PROC_SIDEBAND"
PACK_TYPE"0402"
PART_NUMBER"G21796-074"
LOCATION"R2T33"
TOLERANCE"1%"
VALUE"33.2"
MATERIAL"CHIP"
WATTAGE"1/16W";
"B"
$PN"2"12;
"A"
$PN"1"22;
%"RES"
"1","(2950,3350)","0","mstr_discrete","I42";
;
CDS_SEC"1"
SEC_TYPE"0402"
CDS_LIB"mstr_discrete"
BOM_COST"PROC"
CDS_LOCATION"R2T30"
SEC"1"
ROOM"PROC_SIDEBAND"
PACK_TYPE"0402"
PART_NUMBER"G21796-074"
LOCATION"R2T30"
TOLERANCE"1%"
MATERIAL"CHIP"
WATTAGE"1/16W"
VALUE"33.2";
"B"
$PN"2"13;
"A"
$PN"1"16;
%"RES"
"1","(2950,2575)","0","mstr_discrete","I62";
;
CDS_SEC"1"
SEC_TYPE"0402"
CDS_LIB"mstr_discrete"
BOM_COST"PROC"
CDS_LOCATION"R7D24"
SEC"1"
ROOM"PROC_SIDEBAND"
PACK_TYPE"0402"
PART_NUMBER"G21796-074"
LOCATION"R7D24"
WATTAGE"1/16W"
MATERIAL"CHIP"
TOLERANCE"1%"
VALUE"33.2";
"B"
$PN"2"14;
"A"
$PN"1"17;
%"RES"
"2","(-2325,4050)","0","mstr_discrete","I63";
;
CDS_SEC"1"
CDS_LOCATION"R2T19"
SEC"1"
SEC_TYPE"0402"
ROOM"PROC_SIDEBAND"
BOM_COST"PROC"
CDS_LIB"mstr_discrete"
VALUE"200.0"
LOCATION"R2T19"
TOLERANCE"1%"
PACK_TYPE"0402"
PART_NUMBER"G21796-004"
MATERIAL"CHIP"
WATTAGE"1/16W";
"A"
$PN"1"4;
"B"
$PN"2"36;
%"PVCCIO_CPU0"
"1","(-2325,4300)","0","mstr_symbols","I64";
;
HDL_POWER"PVCCIO_CPU0"
VOLTAGE"1.1V"
CDS_LIB"mstr_symbols"
BODY_TYPE"PLUMBING";
"G\NAC"4;
%"RES"
"1","(-925,3825)","0","mstr_discrete","I67";
;
CDS_SEC"1"
ROOM"PROC_SIDEBAND"
CDS_LOCATION"R2T16"
SEC"1"
SEC_TYPE"0402"
CDS_LIB"mstr_discrete"
PART_NUMBER"G21796-267"
LOCATION"R2T16"
TOLERANCE"1.0%"
PACK_TYPE"0402"
MATERIAL"CHIP"
VALUE"75"
WATTAGE"1/16W";
"B"
$PN"2"32;
"A"
$PN"1"36;
%"RES"
"1","(-925,3300)","0","mstr_discrete","I68";
;
CDS_SEC"1"
SEC"1"
CDS_LOCATION"R2T31"
SEC_TYPE"0402"
ROOM"PROC_SIDEBAND"
CDS_LIB"mstr_discrete"
PART_NUMBER"G21796-267"
LOCATION"R2T31"
VALUE"75"
WATTAGE"1/16W"
MATERIAL"CHIP"
PACK_TYPE"0402"
TOLERANCE"1.0%";
"B"
$PN"2"33;
"A"
$PN"1"37;
%"P3V3"
"1","(1000,4150)","0","mstr_symbols","I70";
;
SIZE"1B"
BODY_TYPE"PLUMBING"
VOLTAGE"3.3V"
CDS_LIB"mstr_symbols"
HDL_POWER"P3V3";
"G\NAC"5;
%"CAP_A"
"1","(1150,3875)","0","dev_discrete","I72";
;
SEC"1"
SEC_TYPE"0402V"
CDS_SEC"1"
CDS_LIB"dev_discrete"
BOM_COST"PROC"
CDS_LOCATION"C2T33"
ROOM"PROC_SIDEBAND"
MATERIAL"X6S"
VOLTAGE"6.3V"
PACK_TYPE"0402V"
TOLERANCE"10%"
VALUE"1.0UF"
PART_NUMBER"D97712-004"
LOCATION"C2T33";
"B"
$PN"2"6;
"A"
$PN"1"5;
%"GND"
"1","(1150,3675)","0","mstr_symbols","I73";
;
HDL_POWER"GND"
SIZE"1B"
VOLTAGE"0"
CDS_LIB"mstr_symbols"
BODY_TYPE"PLUMBING";
"A\NAC"6;
%"PVCCIO_CPU0"
"1","(-2750,2800)","0","mstr_symbols","I78";
;
HDL_POWER"PVCCIO_CPU0"
CDS_LIB"mstr_symbols"
BODY_TYPE"PLUMBING"
VOLTAGE"1.1V";
"G\NAC"7;
%"RES"
"2","(-2750,2525)","0","mstr_discrete","I79";
;
CDS_SEC"1"
SEC_TYPE"0402"
SEC"1"
CDS_LOCATION"R4R3"
BOM_COST"PROC_SIDEBAND"
CDS_LIB"mstr_discrete"
ROOM"PROC_SIDEBAND"
PART_NUMBER"G21796-009"
VALUE"150.0"
LOCATION"R4R3"
TOLERANCE"1%"
WATTAGE"1/16W"
MATERIAL"CHIP"
PACK_TYPE"0402";
"A"
$PN"1"7;
"B"
$PN"2"34;
%"RES"
"2","(-2025,4050)","0","mstr_discrete","I87";
;
CDS_SEC"1"
CDS_LOCATION"R2T26"
SEC"1"
SEC_TYPE"0402"
CDS_LIB"mstr_discrete"
BOM_COST"PROC"
ROOM"PROC_SIDEBAND"
VALUE"200.0"
LOCATION"R2T26"
TOLERANCE"1%"
PACK_TYPE"0402"
PART_NUMBER"G21796-004"
WATTAGE"1/16W"
MATERIAL"CHIP";
"A"
$PN"1"4;
"B"
$PN"2"37;
%"RES"
"2","(-1375,4125)","0","mstr_discrete","I88";
;
CDS_SEC"1"
CDS_LOCATION"R2T57"
SEC"1"
SEC_TYPE"0402"
CDS_LIB"mstr_discrete"
WATTAGE"1/16W"
TOLERANCE"5%"
VALUE"0.0"
LOCATION"R2T57"
PACK_TYPE"0402"
PART_NUMBER"G21497-005"
MATERIAL"EMPTY";
"A"
$PN"1"11;
"B"
$PN"2"36;
%"RES"
"2","(-1100,4125)","0","mstr_discrete","I89";
;
CDS_SEC"1"
CDS_LOCATION"R2T61"
SEC"1"
SEC_TYPE"0402"
CDS_LIB"mstr_discrete"
WATTAGE"1/16W"
TOLERANCE"5%"
VALUE"0.0"
LOCATION"R2T61"
PACK_TYPE"0402"
PART_NUMBER"G21497-005"
MATERIAL"EMPTY";
"A"
$PN"1"10;
"B"
$PN"2"37;
%"RES"
"2","(2025,3850)","0","mstr_discrete","I93";
;
CDS_SEC"1"
CDS_LOCATION"R2T62"
SEC"1"
SEC_TYPE"0402"
CDS_LIB"mstr_discrete"
PART_NUMBER"G21497-005"
LOCATION"R2T62"
TOLERANCE"5%"
VALUE"0.0"
WATTAGE"1/16W"
PACK_TYPE"0402"
MATERIAL"EMPTY";
"A"
$PN"1"10;
"B"
$PN"2"22;
%"RES"
"2","(2400,3850)","0","mstr_discrete","I94";
;
CDS_SEC"1"
CDS_LOCATION"R2T58"
SEC"1"
SEC_TYPE"0402"
CDS_LIB"mstr_discrete"
WATTAGE"1/16W"
PART_NUMBER"G21497-005"
LOCATION"R2T58"
MATERIAL"EMPTY"
VALUE"0.0"
TOLERANCE"5%"
PACK_TYPE"0402";
"A"
$PN"1"11;
"B"
$PN"2"16;
%"CAP_A"
"1","(1925,625)","0","dev_discrete","I95";
;
CDS_SEC"1"
SEC_TYPE"0402V"
SEC"1"
CDS_LOCATION"C2T32"
BOM_COST"PROC"
CDS_LIB"dev_discrete"
ROOM"PROC_SIDEBAND"
MATERIAL"X7R"
VOLTAGE"16V"
PACK_TYPE"0402V"
TOLERANCE"10%"
VALUE"0.1UF"
PART_NUMBER"A36096-030"
LOCATION"C2T32";
"B"
$PN"2"9;
"A"
$PN"1"20;
%"PVCCIO_CPU0"
"1","(2275,1325)","0","mstr_symbols","I96";
;
HDL_POWER"PVCCIO_CPU0"
BODY_TYPE"PLUMBING"
CDS_LIB"mstr_symbols"
VOLTAGE"1.1V";
"G\NAC"8;
%"RES"
"2","(2275,1100)","0","mstr_discrete","I97";
;
CDS_SEC"1"
CDS_LOCATION"R2T36"
SEC_TYPE"0402"
SEC"1"
BOM_COST"PROC"
CDS_LIB"mstr_discrete"
ROOM"PROC_SIDEBAND"
WATTAGE"1/16W"
MATERIAL"CHIP"
TOLERANCE"1%"
LOCATION"R2T36"
VALUE"49.9"
PART_NUMBER"G21796-047"
PACK_TYPE"0402";
"A"
$PN"1"8;
"B"
$PN"2"20;
%"RES"
"2","(2275,575)","0","mstr_discrete","I98";
;
CDS_SEC"1"
ROOM"PROC_SIDEBAND"
SEC"1"
SEC_TYPE"0402"
CDS_LOCATION"R2T39"
BOM_COST"PROC"
CDS_LIB"mstr_discrete"
PART_NUMBER"G21796-017"
LOCATION"R2T39"
WATTAGE"1/16W"
VALUE"100.0"
TOLERANCE"1%"
MATERIAL"CHIP"
PACK_TYPE"0402";
"A"
$PN"1"20;
"B"
$PN"2"9;
%"GND"
"1","(2275,225)","0","mstr_symbols","I99";
;
SIZE"1B"
HDL_POWER"GND"
CDS_LIB"mstr_symbols"
VOLTAGE"0"
BODY_TYPE"PLUMBING";
"A\NAC"9;
END.
